# Lightning_PEB_EQL.xlsx — DPBlength (si-constraints)
| 15669-1.1115WPH1657.brd |  |  |  |
| Date Wed Nov 16 09:23:58 2016 |  |  |  |
| Net Name | Etch Length (mils) | Manhattan Length (mils) | Percent Manhattan (mils) |
| 12V_PRECH_SSD0 | 991.93 | 463.87 | 213.84 |
| 12V_PRECH_SSD1 | 760.9 | 660.95 | 115.12 |
| 12V_PRECH_SSD2 | 729.8 | 691.07 | 105.6 |
| 12V_PRECH_SSD3 | 767.1 | 645.19000000000005 | 118.89 |
| 12V_PRECH_SSD4 | 750.92 | 643.30999999999995 | 116.73 |
| 12V_PRECH_SSD5 | 1030.43 | 460.41 | 223.81 |
| 12V_PRECH_SSD6 | 707.47 | 646.41 | 109.45 |
| 12V_PRECH_SSD7 | 735.17 | 628.53 | 116.97 |
| 12V_PRECH_SSD8 | 781.5 | 647.65 | 120.67 |
| 12V_PRECH_SSD9 | 742.76 | 629.77 | 117.94 |
| 12V_PRECH_SSD10 | 915.51 | 615.98 | 148.63 |
| 12V_PRECH_SSD11 | 840.6 | 596.86 | 140.84 |
| 12V_PRECH_SSD12 | 857.74 | 576.74 | 148.72 |
| 12V_PRECH_SSD13 | 869.48 | 607.62 | 143.1 |
| 12V_PRECH_SSD14 | 987.51 | 538.72 | 183.31 |
| AGND_P3V3 | 1725.91 | 1069.03 | 161.44999999999999 |
| ATTN_LED_DR0_AND | 240.46 | 269.39999999999998 | 89.26 |
| ATTN_LED_DR0_AND_R | 264.64 | 158.75 | 166.7 |
| ATTN_LED_DR0_MOS_N | 333.21 | 345.86 | 96.34 |
| ATTN_LED_DR0_N | 9969.85 | 9528.85 | 104.63 |
| ATTN_LED_DR0_R | 193.8 | 71.25 | 272 |
| ATTN_LED_DR10_AND | 169.41 | 196.6 | 86.17 |
| ATTN_LED_DR10_AND_R | 208.5 | 233.25 | 89.39 |
| ATTN_LED_DR10_MOS_N | 182.86 | 152.94999999999999 | 119.55 |
| ATTN_LED_DR10_N | 3671.87 | 3471.18 | 105.78 |
| ATTN_LED_DR10_R | 254.09 | 321.75 | 78.97 |
| ATTN_LED_DR11_AND | 157.72999999999999 | 169.63 | 92.99 |
| ATTN_LED_DR11_AND_R | 316.91000000000003 | 333.75 | 94.95 |
| ATTN_LED_DR11_MOS_N | 231.95 | 228.62 | 101.46 |
| ATTN_LED_DR11_N | 2466.1999999999998 | 2397.48 | 102.87 |
| ATTN_LED_DR11_R | 149.63999999999999 | 134.87 | 110.95 |
| ATTN_LED_DR12_AND | 160.15 | 169.63 | 94.41 |
| ATTN_LED_DR12_AND_R | 258.93 | 278.63 | 92.93 |
| ATTN_LED_DR12_MOS_N | 227.32 | 226.28 | 100.46 |
| ATTN_LED_DR12_N | 1513.96 | 1853.75 | 81.67 |
| ATTN_LED_DR12_R | 167.36 | 146.6 | 114.16 |
| ATTN_LED_DR13_AND | 159.49 | 169.63 | 94.02 |
| ATTN_LED_DR13_AND_R | 316.91000000000003 | 333.75 | 94.95 |
| ATTN_LED_DR13_MOS_N | 228.19 | 218.74 | 104.32 |
| ATTN_LED_DR13_N | 2224.56 | 2428.7800000000002 | 91.59 |
| ATTN_LED_DR13_R | 160.07 | 134.87 | 118.68 |
| ATTN_LED_DR14_AND | 159.49 | 169.63 | 94.02 |
| ATTN_LED_DR14_AND_R | 316.91000000000003 | 333.75 | 94.95 |
| ATTN_LED_DR14_MOS_N | 222.03 | 226.98 | 97.82 |
| ATTN_LED_DR14_N | 4365.13 | 4640.63 | 94.06 |
| ATTN_LED_DR14_R | 160.07 | 134.87 | 118.68 |
| ATTN_LED_DR1_AND | 240.46 | 269.39999999999998 | 89.26 |
| ATTN_LED_DR1_AND_R | 264.64 | 158.75 | 166.7 |
| ATTN_LED_DR1_MOS_N | 266.27 | 279.39 | 95.3 |
| ATTN_LED_DR1_N | 10457.51 | 11029.78 | 94.81 |
| ATTN_LED_DR1_R | 166.09 | 71.010000000000005 | 233.9 |
| ATTN_LED_DR2_AND | 240.46 | 269.39999999999998 | 89.26 |
| ATTN_LED_DR2_AND_R | 264.64 | 158.75 | 166.7 |
| ATTN_LED_DR2_MOS_N | 289.2 | 337.83 | 85.6 |
| ATTN_LED_DR2_N | 11400.4 | 12391.99 | 92 |
| ATTN_LED_DR2_R | 193.8 | 71.25 | 272 |
| ATTN_LED_DR3_AND | 240.46 | 269.39999999999998 | 89.26 |
| ATTN_LED_DR3_AND_R | 264.64 | 158.75 | 166.7 |
| ATTN_LED_DR3_MOS_N | 338.04 | 342.43 | 98.72 |
| ATTN_LED_DR3_N | 13441.69 | 14651.83 | 91.74 |
| ATTN_LED_DR3_R | 193.8 | 71.25 | 272 |
| ATTN_LED_DR4_AND | 230.46 | 259.39999999999998 | 88.84 |
| ATTN_LED_DR4_AND_R | 264.64 | 158.75 | 166.7 |
| ATTN_LED_DR4_MOS_N | 300.54000000000002 | 304.56 | 98.68 |
| ATTN_LED_DR4_N | 14711.84 | 15251.64 | 96.46 |
| ATTN_LED_DR4_R | 198.28 | 73.03 | 271.51 |
| ATTN_LED_DR5_AND | 177.17 | 160.6 | 110.32 |
| ATTN_LED_DR5_AND_R | 304.13 | 213.75 | 142.28 |
| ATTN_LED_DR5_MOS_N | 1147.6099999999999 | 1025 | 111.96 |
| ATTN_LED_DR5_N | 2811.14 | 2810.84 | 100.01 |
| ATTN_LED_DR5_R | 198.33 | 205.25 | 96.63 |
| ATTN_LED_DR6_AND | 240.46 | 269.39999999999998 | 89.26 |
| ATTN_LED_DR6_AND_R | 224.26 | 158.75 | 141.27000000000001 |
| ATTN_LED_DR6_MOS_N | 384.24 | 421.84 | 91.09 |
| ATTN_LED_DR6_N | 2712.65 | 2234.5 | 121.4 |
| ATTN_LED_DR6_R | 180.42 | 188.17 | 95.88 |
| ATTN_LED_DR7_AND | 197.78 | 195.6 | 101.11 |
| ATTN_LED_DR7_AND_R | 319.20999999999998 | 293.75 | 108.67 |
| ATTN_LED_DR7_MOS_N | 1373.23 | 857.22 | 160.19999999999999 |
| ATTN_LED_DR7_N | 4243.25 | 5045.33 | 84.1 |
| ATTN_LED_DR7_R | 157.81 | 165.25 | 95.5 |
| ATTN_LED_DR8_AND | 152.87 | 181.1 | 84.41 |
| ATTN_LED_DR8_AND_R | 395.12 | 402.05 | 98.28 |
| ATTN_LED_DR8_MOS_N | 554.48 | 606.61 | 91.41 |
| ATTN_LED_DR8_N | 4967.37 | 4948.53 | 100.38 |
| ATTN_LED_DR8_R | 321.83999999999997 | 356.25 | 90.34 |
| ATTN_LED_DR9_AND | 212.16 | 217.39 | 97.59 |
| ATTN_LED_DR9_AND_R | 287.41000000000003 | 148.75 | 193.21 |
| ATTN_LED_DR9_MOS_N | 420.32 | 452.25 | 92.94 |
| ATTN_LED_DR9_N | 6446.87 | 6748.89 | 95.52 |
| ATTN_LED_DR9_R | 139.27000000000001 | 150.25 | 92.69 |
| BMC_I2C_SCL_BUF_8 | 22932.35 | 17226.62 | 133.12 |
| BMC_I2C_SCL_BUF_9 | 11166.25 | 10166.9 | 109.83 |
| BMC_I2C_SDA_BUF_8 | 23076.26 | 17219.919999999998 | 134.01 |
| BMC_I2C_SDA_BUF_9 | 11154.83 | 10036.4 | 111.14 |
| CLK_BUFFER_EU1_VOE_N | 1118.7 | 678.55 | 164.87 |
| CLK_BUFFER_EU2_VOE_N | 744.53 | 507.4 | 146.72999999999999 |
| CLK_BUFFER_EU3_VOE_N | 957.53 | 659.9 | 145.1 |
| CLK_BUFFER_EU4_VOE_N | 619.76 | 284.45 | 217.88 |
| CLK_BUF_EU1_100M_133M# | 300.66000000000003 | 364.75 | 82.43 |
| CLK_BUF_EU1_HIBW_BYPM_LOBW# | 308.66000000000003 | 344.45 | 89.61 |
| CLK_BUF_EU1_SMB_A0_TRI | 195.28 | 184.15 | 106.04 |
| CLK_BUF_EU1_SMB_A1_TRI | 340.14 | 345.1 | 98.56 |
| CLK_BUF_EU2_100M_133M# | 311.89 | 364.75 | 85.51 |
| CLK_BUF_EU2_HIBW_BYPM_LOBW# | 308.66000000000003 | 344.45 | 89.61 |
| CLK_BUF_EU2_SMB_A0_TRI | 199.59 | 204.15 | 97.76 |
| CLK_BUF_EU2_SMB_A1_TRI | 348.93 | 345.1 | 101.11 |
| CLK_BUF_EU3_100M_133M# | 300.66000000000003 | 364.75 | 82.43 |
| CLK_BUF_EU3_HIBW_BYPM_LOBW# | 308.66000000000003 | 344.45 | 89.61 |
| CLK_BUF_EU3_SMB_A0_TRI | 199.59 | 204.15 | 97.76 |
| CLK_BUF_EU3_SMB_A1_TRI | 348.34 | 345.1 | 100.94 |
| CLK_BUF_EU4_100M_133M# | 299.49 | 364.75 | 82.11 |
| CLK_BUF_EU4_HIBW_BYPM_LOBW# | 308.66000000000003 | 344.45 | 89.61 |
| CLK_BUF_EU4_SMB_A0_TRI | 199.59 | 204.15 | 97.76 |
| CLK_BUF_EU4_SMB_A1_TRI | 342.48 | 345.1 | 99.24 |
| DPB_HW_REVISION | 1312.17 | 1374.95 | 95.43 |
| DRV_ACT_0 | 237.4 | 220.27 | 107.78 |
| DRV_ACT_1 | 237.35 | 220.15 | 107.81 |
| DRV_ACT_2 | 237.3 | 220.04 | 107.85 |
| DRV_ACT_3 | 237.25 | 219.92 | 107.88 |
| DRV_ACT_4 | 237.2 | 219.8 | 107.92 |
| DRV_ACT_5 | 223.43 | 223.73 | 99.87 |
| DRV_ACT_6 | 186.67 | 178.69 | 104.46 |
| DRV_ACT_7 | 243.48 | 243.5 | 99.99 |
| DRV_ACT_8 | 226.51 | 233.38 | 97.05 |
| DRV_ACT_9 | 235.31 | 248.26 | 94.78 |
| DRV_ACT_10 | 267.52999999999997 | 252.55 | 105.93 |
| DRV_ACT_11 | 239.02 | 227.43 | 105.1 |
| DRV_ACT_12 | 238.97 | 227.31 | 105.13 |
| DRV_ACT_13 | 233.93 | 227.2 | 102.96 |
| DRV_ACT_14 | 238.88 | 227.08 | 105.2 |
| DRV_ATTN_0 | 177.01 | 183.11 | 96.67 |
| DRV_ATTN_1 | 177.01 | 183.11 | 96.67 |
| DRV_ATTN_2 | 177.01 | 183.11 | 96.67 |
| DRV_ATTN_3 | 177.01 | 183.11 | 96.67 |
| DRV_ATTN_4 | 177.01 | 183.11 | 96.67 |
| DRV_ATTN_5 | 192.03 | 221.57 | 86.67 |
| DRV_ATTN_6 | 137.97 | 146.69 | 94.06 |
| DRV_ATTN_7 | 197.99 | 221.8 | 89.26 |
| DRV_ATTN_8 | 195.11 | 221.92 | 87.92 |
| DRV_ATTN_9 | 196.02 | 217.04 | 90.31 |
| DRV_ATTN_10 | 188.33 | 199.55 | 94.38 |
| DRV_ATTN_11 | 180.42 | 171.37 | 105.28 |
| DRV_ATTN_12 | 180.37 | 171.49 | 105.18 |
| DRV_ATTN_13 | 180.32 | 171.6 | 105.08 |
| DRV_ATTN_14 | 170.95 | 171.72 | 99.55 |
| DUALPORTEN#0 | 402.4 | 364.82 | 110.3 |
| DUALPORTEN#1 | 382.81 | 399.84 | 95.74 |
| DUALPORTEN#2 | 392.45 | 408.96 | 95.96 |
| DUALPORTEN#3 | 376.91 | 394.08 | 95.64 |
| DUALPORTEN#4 | 396.39 | 410.7 | 96.52 |
| DUALPORTEN#5 | 346.79 | 386.36 | 89.76 |
| DUALPORTEN#6 | 487.57 | 474.24 | 102.81 |
| DUALPORTEN#7 | 388.67 | 396.5 | 98.03 |
| DUALPORTEN#8 | 389.48 | 397.34 | 98.02 |
| DUALPORTEN#9 | 426.35 | 432.96 | 98.47 |
| DUALPORTEN#10 | 393.44 | 397.05 | 99.09 |
| DUALPORTEN#11 | 384.08 | 389.93 | 98.5 |
| DUALPORTEN#12 | 397.96 | 408.89 | 97.33 |
| DUALPORTEN#13 | 375.93 | 382.69 | 98.23 |
| DUALPORTEN#14 | 395.72 | 420.15 | 94.19 |
| EEPROM_A0 | 212.87 | 243.1 | 87.57 |
| EEPROM_A1 | 181.55 | 188.7 | 96.21 |
| EEPROM_A2 | 193.98 | 178.7 | 108.55 |
| EEPROM_SCL | 179.73 | 184.3 | 97.52 |
| EEPROM_SDA | 191.66 | 183.1 | 104.68 |
| EEPROM_WP | 198.12 | 198.7 | 99.71 |
| FCB_HW_REVISION | 13199.68 | 11350.32 | 116.29 |
| GND | 68223.48 | 155202.47 | 43.96 |
| I2C8_SCL_R_SW_EU16 | 191.96 | 202.29 | 94.89 |
| I2C8_SCL_R_SW_EU17 | 199.93 | 222.29 | 89.94 |
| I2C8_SDA_R_SW_EU16 | 149.55000000000001 | 184.97 | 80.849999999999994 |
| I2C8_SDA_R_SW_EU17 | 169.55 | 204.97 | 82.72 |
| I2C_B_SCL | 33815.53 | 31590 | 107.05 |
| I2C_B_SDA | 33740.35 | 31690 | 106.47 |
| I2C_B_TMP1_A0 | 224.43 | 235.19 | 95.42 |
| I2C_B_TMP1_A1 | 244.89 | 284.58999999999997 | 86.05 |
| I2C_B_TMP1_A2 | 278.52999999999997 | 333.99 | 83.4 |
| I2C_B_TMP1_ALERT | 152.43 | 166.65 | 91.47 |
| I2C_B_TMP2_A0 | 317.88 | 384.47 | 82.68 |
| I2C_B_TMP2_A1 | 228.64 | 253.87 | 90.06 |
| I2C_B_TMP2_A2 | 157.75 | 161.66999999999999 | 97.57 |
| I2C_B_TMP2_ALERT | 158.47999999999999 | 189.57 | 83.6 |
| I2C_B_TMP3_A0 | 302.16000000000003 | 367.73 | 82.17 |
| I2C_B_TMP3_A1 | 232.06 | 262.13 | 88.53 |
| I2C_B_TMP3_A2 | 154.6 | 156.53 | 98.77 |
| I2C_B_TMP3_ALERT | 157.76 | 187.83 | 83.99 |
| I2C_B_TMP4_A0 | 301.12 | 367.93 | 81.84 |
| I2C_B_TMP4_A1 | 231.01 | 262.33 | 88.06 |
| I2C_B_TMP4_A2 | 155.93 | 156.72999999999999 | 99.49 |
| I2C_B_TMP4_ALERT | 156.71 | 188.03 | 83.35 |
| I2C_C_SCL | 634.97 | 565.96 | 112.19 |
| I2C_C_SDA | 634.09 | 565.96 | 112.04 |
| I2C_MUX_RESET | 8617.82 | 7970 | 108.13 |
| I2C_MUX_RESET_PEB | 5924.95 | 6319.99 | 93.75 |
| I2C_MUX_RESET_R_EU16 | 244.97 | 322.29000000000002 | 76.010000000000005 |
| I2C_MUX_RESET_R_EU17 | 245.55 | 322.29000000000002 | 76.19 |
| I2C_SCL_BUF_8_EU3_R | 257.29000000000002 | 284.75 | 90.36 |
| I2C_SCL_BUF_8_EU4_R | 258.45999999999998 | 284.75 | 90.77 |
| I2C_SCL_BUF_9_EU1_R | 245.29 | 284.75 | 86.14 |
| I2C_SCL_BUF_9_EU2_R | 261.39 | 284.75 | 91.8 |
| I2C_SDA_BUF_8_EU3_R | 247.43 | 264.45 | 93.56 |
| I2C_SDA_BUF_8_EU4_R | 231.59 | 264.45 | 87.57 |
| I2C_SDA_BUF_9_EU1_R | 240.4 | 264.45 | 90.91 |
| I2C_SDA_BUF_9_EU2_R | 235.63 | 264.45 | 89.1 |
| I2C_SW_EU16_ADDRESS_A0 | 233.24 | 244.66 | 95.33 |
| I2C_SW_EU16_ADDRESS_A1 | 255.35 | 304.97000000000003 | 83.73 |
| I2C_SW_EU16_ADDRESS_A2 | 217.52 | 242.29 | 89.78 |
| I2C_SW_EU17_ADDRESS_A0 | 229.92 | 244.66 | 93.98 |
| I2C_SW_EU17_ADDRESS_A1 | 254.9 | 304.97000000000003 | 83.58 |
| I2C_SW_EU17_ADDRESS_A2 | 194.11 | 247.29 | 78.489999999999995 |
| N70914768 | 394.09 | 396.42 | 99.41 |
| N70929042 | 366.01 | 338.46 | 108.14 |
| N70930468 | 445.51 | 506.42 | 87.97 |
| P12V | 1344.95 | 67909.179999999993 | 1.98 |
| P12V_MOST0_GATE | 172.95 | 158.75 | 108.94 |
| P12V_MOST0_GATE_D | 154.21 | 183.5 | 84.04 |
| P12V_MOST10_GATE | 187.09 | 178.75 | 104.67 |
| P12V_MOST10_GATE_D | 173.68 | 131.5 | 132.07 |
| P12V_MOST11_GATE | 172.95 | 158.75 | 108.94 |
| P12V_MOST11_GATE_D | 179.02 | 124.5 | 143.79 |
| P12V_MOST12_GATE | 172.95 | 158.75 | 108.94 |
| P12V_MOST12_GATE_D | 181.62 | 129.5 | 140.25 |
| P12V_MOST13_GATE | 172.95 | 158.75 | 108.94 |
| P12V_MOST13_GATE_D | 188.03 | 115.5 | 162.80000000000001 |
| P12V_MOST14_GATE | 172.95 | 158.75 | 108.94 |
| P12V_MOST14_GATE_D | 166.39 | 158.5 | 104.98 |
| P12V_MOST1_GATE | 172.95 | 158.75 | 108.94 |
| P12V_MOST1_GATE_D | 271.91000000000003 | 165.5 | 164.3 |
| P12V_MOST2_GATE | 172.95 | 158.75 | 108.94 |
| P12V_MOST2_GATE_D | 270.63 | 150.5 | 179.82 |
| P12V_MOST3_GATE | 172.95 | 158.75 | 108.94 |
| P12V_MOST3_GATE_D | 286.02 | 150.5 | 190.04 |
| P12V_MOST4_GATE | 172.95 | 158.75 | 108.94 |
| P12V_MOST4_GATE_D | 269.75 | 155.5 | 173.47 |
| P12V_MOST5_GATE | 177.44 | 153.75 | 115.41 |
| P12V_MOST5_GATE_D | 147.38 | 175.5 | 83.98 |
| P12V_MOST6_GATE | 172.95 | 158.75 | 108.94 |
| P12V_MOST6_GATE_D | 146.12 | 167.5 | 87.24 |
| P12V_MOST7_GATE | 172.95 | 158.75 | 108.94 |
| P12V_MOST7_GATE_D | 206.48 | 114.5 | 180.33 |
| P12V_MOST8_GATE | 172.95 | 158.75 | 108.94 |
| P12V_MOST8_GATE_D | 168.83 | 130.5 | 129.37 |
| P12V_MOST9_GATE | 172.95 | 158.75 | 108.94 |
| P12V_MOST9_GATE_D | 197.7 | 131.5 | 150.34 |
| P12V_SENSE | 331.58 | 371.3 | 89.3 |
| P12V_SSD0 | 494.24 | 1422.43 | 34.75 |
| P12V_SSD1 | 95.57 | 1495.67 | 6.39 |
| P12V_SSD2 | 77.36 | 1428.27 | 5.42 |
| P12V_SSD3 | 70 | 1429.91 | 4.9000000000000004 |
| P12V_SSD4 | 66 | 1431.03 | 4.6100000000000003 |
| P12V_SSD5 | 491.78 | 1413.75 | 34.79 |
| P12V_SSD6 | 243.29 | 1541.37 | 15.78 |
| P12V_SSD7 | 69 | 1412.49 | 4.88 |
| P12V_SSD8 | 51 | 1339.93 | 3.81 |
| P12V_SSD9 | 47 | 1357.05 | 3.46 |
| P12V_SSD10 | 55.43 | 1455.88 | 3.81 |
| P12V_SSD11 | 56 | 1321.24 | 4.24 |
| P12V_SSD12 | 49 | 1380.64 | 3.55 |
| P12V_SSD13 | 51 | 1391.02 | 3.67 |
| P12V_SSD14 | 2527.4899999999998 | 3788.34 | 66.72 |
| P12V_SSD14_SENSE | 198.48 | 199.65 | 99.41 |
| P3V3 | 84724.75 | 114437.83 | 74.040000000000006 |
| P3V3_CC | 1595.01 | 1382.5 | 115.37 |
| P3V3_CC_R | 328.39 | 247.5 | 132.68 |
| P3V3_EN_R | 191.92 | 192.6 | 99.65 |
| P3V3_OUT | 323.5 | 990.57 | 32.659999999999997 |
| P3V3_PG | 21610.240000000002 | 19874.05 | 108.74 |
| P3V3_SENSE | 196.06 | 196.65 | 99.7 |
| P3V3_SNB | 72.459999999999994 | 83 | 87.3 |
| P3V3_SS | 199.79 | 232.1 | 86.08 |
| P3V3_SW | 418.9 | 736.95 | 56.84 |
| P3V3_VBST | 105.27 | 131.91 | 79.81 |
| P3V3_VBST_RR | 50.18 | 57.5 | 87.27 |
| P3V3_VCC | 187.79 | 199.6 | 94.08 |
| P3V3_VFB | 258.2 | 281.91000000000003 | 91.59 |
| P3V3_VFB_R | 1189.5899999999999 | 712.5 | 166.96 |
| P3V3_VIN | 0 | 475.64 | 0 |
| P3V3_VO | 178.73 | 221.91 | 80.540000000000006 |
| P3V3_VRG5 | 242.55 | 252.1 | 96.21 |
| PCIE_MATED#_A | 567.29 | 645.04999999999995 | 87.94 |
| PCIE_MATED#_B | 1738.85 | 1630.33 | 106.66 |
| PEER_1A&2A_HB | 13194.87 | 11437.32 | 115.37 |
| PEER_TRAY_PRESENT | 13226.03 | 11629.8 | 113.73 |
| PE_100M_CLK1_C_N | 442.66 | 406.24 | 108.96 |
| PE_100M_CLK1_C_P | 442.79 | 473.73 | 93.47 |
| PE_100M_CLK1_N | 14558.13 | 14191.9 | 102.58 |
| PE_100M_CLK1_P | 14558.9 | 14117.2 | 103.13 |
| PE_100M_CLK2_C_N | 388.91 | 294.23 | 132.18 |
| PE_100M_CLK2_C_P | 388.25 | 297.74 | 130.4 |
| PE_100M_CLK2_N | 10303.459999999999 | 10051.299999999999 | 102.51 |
| PE_100M_CLK2_P | 10303.299999999999 | 9976.7000000000007 | 103.27 |
| PE_100M_CLK3_C_N | 1310.73 | 1327.67 | 98.72 |
| PE_100M_CLK3_C_P | 1310.1199999999999 | 1331.17 | 98.42 |
| PE_100M_CLK3_N | 7707.67 | 7760.56 | 99.32 |
| PE_100M_CLK3_P | 7707.7 | 7684.96 | 100.3 |
| PE_100M_CLK4_C_N | 251.18 | 295.92 | 84.88 |
| PE_100M_CLK4_C_P | 251.28 | 292.42 | 85.93 |
| PE_100M_CLK4_N | 4009.4 | 4035.3 | 99.36 |
| PE_100M_CLK4_P | 4009.89 | 3959.7 | 101.27 |
| PE_CLK100M_DR0_1_N | 5342.75 | 5825.97 | 91.71 |
| PE_CLK100M_DR0_1_P | 5342.74 | 5834.47 | 91.57 |
| PE_CLK100M_DR0_2_N | 6519.18 | 6432.27 | 101.35 |
| PE_CLK100M_DR0_2_P | 6519.83 | 6440.77 | 101.23 |
| PE_CLK100M_DR10_1_N | 4095.23 | 3889.9 | 105.28 |
| PE_CLK100M_DR10_1_P | 4096.16 | 3881.4 | 105.53 |
| PE_CLK100M_DR10_2_N | 3677.1 | 3534.78 | 104.03 |
| PE_CLK100M_DR10_2_P | 3677.01 | 3526.28 | 104.27 |
| PE_CLK100M_DR11_1_N | 3526.55 | 3914.78 | 90.08 |
| PE_CLK100M_DR11_1_P | 3525.6 | 3986.28 | 88.44 |
| PE_CLK100M_DR11_2_N | 3692.85 | 3859.66 | 95.68 |
| PE_CLK100M_DR11_2_P | 3692.56 | 3931.16 | 93.93 |
| PE_CLK100M_DR12_1_N | 3161.41 | 3574.66 | 88.44 |
| PE_CLK100M_DR12_1_P | 3161.3 | 3646.16 | 86.7 |
| PE_CLK100M_DR12_2_N | 3553.73 | 3519.54 | 100.97 |
| PE_CLK100M_DR12_2_P | 3553.44 | 3591.04 | 98.95 |
| PE_CLK100M_DR13_1_N | 3477.9 | 3819.54 | 91.06 |
| PE_CLK100M_DR13_1_P | 3477.96 | 3891.04 | 89.38 |
| PE_CLK100M_DR13_2_N | 3654.04 | 3764.42 | 97.07 |
| PE_CLK100M_DR13_2_P | 3653.94 | 3835.92 | 95.26 |
| PE_CLK100M_DR14_1_N | 5256.75 | 5080.3 | 103.47 |
| PE_CLK100M_DR14_1_P | 5256.84 | 5008.8 | 104.95 |
| PE_CLK100M_DR14_2_N | 4758.8599999999997 | 5386.6 | 88.35 |
| PE_CLK100M_DR14_2_P | 4758.97 | 5315.1 | 89.54 |
| PE_CLK100M_DR1_1_N | 5603.73 | 6755.85 | 82.95 |
| PE_CLK100M_DR1_1_P | 5603.73 | 6764.35 | 82.84 |
| PE_CLK100M_DR1_2_N | 6885.78 | 7362.15 | 93.53 |
| PE_CLK100M_DR1_2_P | 6885.11 | 7370.65 | 93.41 |
| PE_CLK100M_DR2_1_N | 5816.82 | 6337.81 | 91.78 |
| PE_CLK100M_DR2_1_P | 5815.88 | 6409.31 | 90.74 |
| PE_CLK100M_DR2_2_N | 7376.49 | 6282.69 | 117.41 |
| PE_CLK100M_DR2_2_P | 7376.67 | 6354.19 | 116.09 |
| PE_CLK100M_DR3_1_N | 6664.81 | 6867.93 | 97.04 |
| PE_CLK100M_DR3_1_P | 6664.8 | 6859.43 | 97.16 |
| PE_CLK100M_DR3_2_N | 7846.2 | 6512.81 | 120.47 |
| PE_CLK100M_DR3_2_P | 7846.84 | 6504.31 | 120.64 |
| PE_CLK100M_DR4_1_N | 8072.76 | 10798.05 | 74.760000000000005 |
| PE_CLK100M_DR4_1_P | 8072.26 | 10869.55 | 74.260000000000005 |
| PE_CLK100M_DR4_2_N | 9636.5300000000007 | 10742.93 | 89.7 |
| PE_CLK100M_DR4_2_P | 9636.91 | 10814.43 | 89.11 |
| PE_CLK100M_DR5_1_N | 2776.13 | 2810.89 | 98.76 |
| PE_CLK100M_DR5_1_P | 2777.05 | 2819.39 | 98.5 |
| PE_CLK100M_DR5_2_N | 2887.91 | 3166.01 | 91.22 |
| PE_CLK100M_DR5_2_P | 2886.98 | 3174.51 | 90.94 |
| PE_CLK100M_DR6_1_N | 3403.55 | 4095.77 | 83.1 |
| PE_CLK100M_DR6_1_P | 3403.66 | 4104.2700000000004 | 82.93 |
| PE_CLK100M_DR6_2_N | 3656.9 | 4450.8900000000003 | 82.16 |
| PE_CLK100M_DR6_2_P | 3656.81 | 4459.3900000000003 | 82 |
| PE_CLK100M_DR7_1_N | 3255.64 | 3755.65 | 86.69 |
| PE_CLK100M_DR7_1_P | 3255.75 | 3764.15 | 86.49 |
| PE_CLK100M_DR7_2_N | 3523 | 4110.7700000000004 | 85.7 |
| PE_CLK100M_DR7_2_P | 3522.9 | 4119.2700000000004 | 85.52 |
| PE_CLK100M_DR8_1_N | 3434.16 | 4000.53 | 85.84 |
| PE_CLK100M_DR8_1_P | 3434.25 | 4009.03 | 85.66 |
| PE_CLK100M_DR8_2_N | 3618.98 | 4355.6499999999996 | 83.09 |
| PE_CLK100M_DR8_2_P | 3618.87 | 4364.1499999999996 | 82.92 |
| PE_CLK100M_DR9_1_N | 3475.73 | 3607.97 | 96.33 |
| PE_CLK100M_DR9_1_P | 3476.01 | 3599.47 | 96.57 |
| PE_CLK100M_DR9_2_N | 2810.35 | 3001.67 | 93.63 |
| PE_CLK100M_DR9_2_P | 2811.28 | 2993.17 | 93.92 |
| PE_CLK_100M_DR0_1_R_N | 231.09 | 270.39999999999998 | 85.46 |
| PE_CLK_100M_DR0_1_R_P | 231.09 | 250.1 | 92.4 |
| PE_CLK_100M_DR0_2_R_N | 172.57 | 199.15 | 86.65 |
| PE_CLK_100M_DR0_2_R_P | 172.55 | 178.8 | 96.51 |
| PE_CLK_100M_DR10_1_R_N | 183.06 | 204.15 | 89.67 |
| PE_CLK_100M_DR10_1_R_P | 183.04 | 224.45 | 81.55 |
| PE_CLK_100M_DR10_2_R_N | 243.2 | 275.39999999999998 | 88.31 |
| PE_CLK_100M_DR10_2_R_P | 243.56 | 290.68 | 83.79 |
| PE_CLK_100M_DR11_1_R_N | 239.87 | 290.68 | 82.52 |
| PE_CLK_100M_DR11_1_R_P | 240.11 | 275.39999999999998 | 87.19 |
| PE_CLK_100M_DR11_2_R_N | 188.33 | 224.45 | 83.91 |
| PE_CLK_100M_DR11_2_R_P | 188.33 | 204.15 | 92.25 |
| PE_CLK_100M_DR12_1_R_N | 247.34 | 290.68 | 85.09 |
| PE_CLK_100M_DR12_1_R_P | 247.14 | 275.39999999999998 | 89.74 |
| PE_CLK_100M_DR12_2_R_N | 183.05 | 224.45 | 81.56 |
| PE_CLK_100M_DR12_2_R_P | 183.06 | 204.15 | 89.67 |
| PE_CLK_100M_DR13_1_R_N | 246.41 | 290.68 | 84.77 |
| PE_CLK_100M_DR13_1_R_P | 246.55 | 275.39999999999998 | 89.52 |
| PE_CLK_100M_DR13_2_R_N | 183.05 | 224.45 | 81.56 |
| PE_CLK_100M_DR13_2_R_P | 183.06 | 204.15 | 89.67 |
| PE_CLK_100M_DR14_1_R_N | 229.2 | 270.39999999999998 | 84.76 |
| PE_CLK_100M_DR14_1_R_P | 229.2 | 250.1 | 91.64 |
| PE_CLK_100M_DR14_2_R_N | 172.57 | 199.15 | 86.65 |
| PE_CLK_100M_DR14_2_R_P | 172.55 | 178.8 | 96.51 |
| PE_CLK_100M_DR1_1_R_N | 229.78 | 270.39999999999998 | 84.98 |
| PE_CLK_100M_DR1_1_R_P | 229.78 | 250.1 | 91.88 |
| PE_CLK_100M_DR1_2_R_N | 172.56 | 199.15 | 86.65 |
| PE_CLK_100M_DR1_2_R_P | 172.58 | 178.8 | 96.52 |
| PE_CLK_100M_DR2_1_R_N | 232.14 | 270.39999999999998 | 85.85 |
| PE_CLK_100M_DR2_1_R_P | 232.13 | 250.1 | 92.82 |
| PE_CLK_100M_DR2_2_R_N | 172.56 | 199.15 | 86.65 |
| PE_CLK_100M_DR2_2_R_P | 172.55 | 178.8 | 96.51 |
| PE_CLK_100M_DR3_1_R_N | 173.39 | 178.8 | 96.97 |
| PE_CLK_100M_DR3_1_R_P | 172.56 | 199.15 | 86.65 |
| PE_CLK_100M_DR3_2_R_N | 223.75 | 250.1 | 89.47 |
| PE_CLK_100M_DR3_2_R_P | 223.76 | 270.39999999999998 | 82.75 |
| PE_CLK_100M_DR4_1_R_N | 174.18 | 205.4 | 84.8 |
| PE_CLK_100M_DR4_1_R_P | 175.16 | 185.1 | 94.63 |
| PE_CLK_100M_DR4_2_R_N | 165.83 | 162.55000000000001 | 102.02 |
| PE_CLK_100M_DR4_2_R_P | 165.81 | 182.9 | 90.66 |
| PE_CLK_100M_DR5_1_R_N | 238.59 | 290.68 | 82.08 |
| PE_CLK_100M_DR5_1_R_P | 238.57 | 275.39999999999998 | 86.63 |
| PE_CLK_100M_DR5_2_R_N | 183.05 | 224.45 | 81.56 |
| PE_CLK_100M_DR5_2_R_P | 183.06 | 204.15 | 89.67 |
| PE_CLK_100M_DR6_1_R_N | 172.55 | 178.8 | 96.51 |
| PE_CLK_100M_DR6_1_R_P | 172.56 | 199.15 | 86.65 |
| PE_CLK_100M_DR6_2_R_N | 232.01 | 250.1 | 92.77 |
| PE_CLK_100M_DR6_2_R_P | 232.02 | 270.39999999999998 | 85.8 |
| PE_CLK_100M_DR7_1_R_N | 172.55 | 178.8 | 96.51 |
| PE_CLK_100M_DR7_1_R_P | 172.56 | 199.15 | 86.65 |
| PE_CLK_100M_DR7_2_R_N | 223.75 | 250.1 | 89.47 |
| PE_CLK_100M_DR7_2_R_P | 223.76 | 270.39999999999998 | 82.75 |
| PE_CLK_100M_DR8_1_R_N | 172.55 | 178.8 | 96.51 |
| PE_CLK_100M_DR8_1_R_P | 172.56 | 199.15 | 86.65 |
| PE_CLK_100M_DR8_2_R_N | 223.75 | 250.1 | 89.47 |
| PE_CLK_100M_DR8_2_R_P | 223.76 | 270.39999999999998 | 82.75 |
| PE_CLK_100M_DR9_1_R_N | 183.06 | 204.15 | 89.67 |
| PE_CLK_100M_DR9_1_R_P | 183.04 | 224.45 | 81.55 |
| PE_CLK_100M_DR9_2_R_N | 246.54 | 275.39999999999998 | 89.52 |
| PE_CLK_100M_DR9_2_R_P | 246.4 | 290.68 | 84.77 |
| PE_RX1_DR0_N | 10182.700000000001 | 10810.21 | 94.2 |
| PE_RX1_DR0_P | 10182.27 | 10810.2 | 94.19 |
| PE_RX1_DR10_N | 3595.8 | 2535.41 | 141.82 |
| PE_RX1_DR10_P | 3596.5 | 2598.4 | 138.41 |
| PE_RX1_DR11_N | 1362.03 | 1236.18 | 110.18 |
| PE_RX1_DR11_P | 1361.43 | 1173.19 | 116.04 |
| PE_RX1_DR12_N | 3918.81 | 2015.71 | 194.41 |
| PE_RX1_DR12_P | 3918.02 | 1952.72 | 200.64 |
| PE_RX1_DR13_N | 2600.88 | 1892.26 | 137.44999999999999 |
| PE_RX1_DR13_P | 2600.6 | 1955.24 | 133.01 |
| PE_RX1_DR14_N | 5517.26 | 5443.44 | 101.36 |
| PE_RX1_DR14_P | 5517.79 | 5506.43 | 100.21 |
| PE_RX1_DR1_N | 9224.75 | 9648.93 | 95.6 |
| PE_RX1_DR1_P | 9224.4699999999993 | 9648.94 | 95.6 |
| PE_RX1_DR2_N | 9545.4699999999993 | 11011.14 | 86.69 |
| PE_RX1_DR2_P | 9545.43 | 11011.15 | 86.69 |
| PE_RX1_DR3_N | 11078.47 | 13869.41 | 79.88 |
| PE_RX1_DR3_P | 11078.3 | 13869.42 | 79.88 |
| PE_RX1_DR4_N | 12577.79 | 15515.08 | 81.069999999999993 |
| PE_RX1_DR4_P | 12577.82 | 15515.09 | 81.069999999999993 |
| PE_RX1_DR5_N | 2407.0500000000002 | 2802.33 | 85.89 |
| PE_RX1_DR5_P | 2407.2199999999998 | 2802.34 | 85.9 |
| PE_RX1_DR6_N | 1778.96 | 2164.5300000000002 | 82.19 |
| PE_RX1_DR6_P | 1778.93 | 2164.5300000000002 | 82.19 |
| PE_RX1_DR7_N | 2396.08 | 3034.77 | 78.95 |
| PE_RX1_DR7_P | 2396.08 | 3034.78 | 78.95 |
| PE_RX1_DR8_N | 2388.19 | 3042.65 | 78.489999999999995 |
| PE_RX1_DR8_P | 2388.17 | 3042.65 | 78.489999999999995 |
| PE_RX1_DR9_N | 6704.35 | 6310.36 | 106.24 |
| PE_RX1_DR9_P | 6704.35 | 6310.37 | 106.24 |
| PE_RX2_DR0_N | 10157.67 | 11062.17 | 91.82 |
| PE_RX2_DR0_P | 10157.14 | 11062.17 | 91.82 |
| PE_RX2_DR10_N | 3114.96 | 1905.49 | 163.47 |
| PE_RX2_DR10_P | 3115.67 | 1968.48 | 158.28 |
| PE_RX2_DR11_N | 2302.9699999999998 | 1041.8499999999999 | 221.05 |
| PE_RX2_DR11_P | 2303.58 | 1104.8499999999999 | 208.5 |
| PE_RX2_DR12_N | 3521.23 | 1385.79 | 254.1 |
| PE_RX2_DR12_P | 3520.59 | 1322.8 | 266.14999999999998 |
| PE_RX2_DR13_N | 2889.56 | 2522.17 | 114.57 |
| PE_RX2_DR13_P | 2890.27 | 2585.17 | 111.8 |
| PE_RX2_DR14_N | 6084.91 | 6073.36 | 100.19 |
| PE_RX2_DR14_P | 6085.23 | 6136.35 | 99.17 |
| PE_RX2_DR1_N | 9035.0400000000009 | 9270.98 | 97.46 |
| PE_RX2_DR1_P | 9034.94 | 9270.98 | 97.45 |
| PE_RX2_DR2_N | 9618.1200000000008 | 10633.2 | 90.45 |
| PE_RX2_DR2_P | 9618.0300000000007 | 10633.19 | 90.45 |
| PE_RX2_DR3_N | 11056.54 | 13491.47 | 81.95 |
| PE_RX2_DR3_P | 11056.53 | 13491.46 | 81.95 |
| PE_RX2_DR4_N | 12587.98 | 15137.14 | 83.16 |
| PE_RX2_DR4_P | 12587.92 | 15137.14 | 83.16 |
| PE_RX2_DR5_N | 2694.53 | 3180.29 | 84.73 |
| PE_RX2_DR5_P | 2694.57 | 3180.28 | 84.73 |
| PE_RX2_DR6_N | 2316.02 | 2542.48 | 91.09 |
| PE_RX2_DR6_P | 2316.0300000000002 | 2542.48 | 91.09 |
| PE_RX2_DR7_N | 2068.34 | 2656.82 | 77.849999999999994 |
| PE_RX2_DR7_P | 2068.3200000000002 | 2656.82 | 77.849999999999994 |
| PE_RX2_DR8_N | 2061.2600000000002 | 2664.7 | 77.349999999999994 |
| PE_RX2_DR8_P | 2061.23 | 2664.7 | 77.349999999999994 |
| PE_RX2_DR9_N | 6387.53 | 5932.42 | 107.67 |
| PE_RX2_DR9_P | 6387.51 | 5932.42 | 107.67 |
| PE_RX3_DR0_N | 10292.31 | 11125.17 | 92.51 |
| PE_RX3_DR0_P | 10292.31 | 11125.17 | 92.51 |
| PE_RX3_DR10_N | 2852.29 | 1590.52 | 179.33 |
| PE_RX3_DR10_P | 2852.88 | 1653.52 | 172.53 |
| PE_RX3_DR11_N | 2635.88 | 1356.82 | 194.27 |
| PE_RX3_DR11_P | 2636.62 | 1419.81 | 185.7 |
| PE_RX3_DR12_N | 3381.96 | 1070.83 | 315.83 |
| PE_RX3_DR12_P | 3381.2 | 1007.83 | 335.49 |
| PE_RX3_DR13_N | 3194.59 | 2837.14 | 112.6 |
| PE_RX3_DR13_P | 3195.06 | 2900.13 | 110.17 |
| PE_RX3_DR14_N | 6470.1 | 6388.32 | 101.28 |
| PE_RX3_DR14_P | 6469.99 | 6451.32 | 100.29 |
| PE_RX3_DR1_N | 9000.83 | 9207.99 | 97.75 |
| PE_RX3_DR1_P | 9000.7999999999993 | 9207.98 | 97.75 |
| PE_RX3_DR2_N | 9702.44 | 10570.2 | 91.79 |
| PE_RX3_DR2_P | 9702.3799999999992 | 10570.2 | 91.79 |
| PE_RX3_DR3_N | 11107.93 | 13428.47 | 82.72 |
| PE_RX3_DR3_P | 11107.92 | 13428.47 | 82.72 |
| PE_RX3_DR4_N | 12497.44 | 16853.669999999998 | 74.150000000000006 |
| PE_RX3_DR4_P | 12497.42 | 16853.669999999998 | 74.150000000000006 |
| PE_RX3_DR5_N | 2707.26 | 3243.28 | 83.47 |
| PE_RX3_DR5_P | 2707.31 | 3243.28 | 83.47 |
| PE_RX3_DR6_N | 2268.5700000000002 | 2605.48 | 87.07 |
| PE_RX3_DR6_P | 2268.5500000000002 | 2605.48 | 87.07 |
| PE_RX3_DR7_N | 2013.83 | 2593.83 | 77.64 |
| PE_RX3_DR7_P | 2013.8 | 2593.83 | 77.64 |
| PE_RX3_DR8_N | 2036.12 | 2601.71 | 78.260000000000005 |
| PE_RX3_DR8_P | 2036.08 | 2601.6999999999998 | 78.260000000000005 |
| PE_RX3_DR9_N | 6418.17 | 6058.4 | 105.94 |
| PE_RX3_DR9_P | 6418.43 | 6058.4 | 105.94 |
| PE_RX4_DR0_N | 10467.57 | 11188.16 | 93.56 |
| PE_RX4_DR0_P | 10467.49 | 11188.16 | 93.56 |
| PE_RX4_DR10_N | 2675.15 | 1275.57 | 209.72 |
| PE_RX4_DR10_P | 2675.78 | 1338.55 | 199.9 |
| PE_RX4_DR11_N | 2959.34 | 1671.78 | 177.02 |
| PE_RX4_DR11_P | 2960.07 | 1734.77 | 170.63 |
| PE_RX4_DR12_N | 3270.19 | 892.26 | 366.51 |
| PE_RX4_DR12_P | 3269.95 | 955.24 | 342.32 |
| PE_RX4_DR13_N | 3489.03 | 3152.1 | 110.69 |
| PE_RX4_DR13_P | 3489.49 | 3215.09 | 108.53 |
| PE_RX4_DR14_N | 6775.55 | 6703.28 | 101.08 |
| PE_RX4_DR14_P | 6775.84 | 6766.27 | 100.14 |
| PE_RX4_DR1_N | 8966.26 | 9144.99 | 98.05 |
| PE_RX4_DR1_P | 8966.25 | 9145 | 98.05 |
| PE_RX4_DR2_N | 9760.4599999999991 | 10507.21 | 92.89 |
| PE_RX4_DR2_P | 9760.4 | 10507.21 | 92.89 |
| PE_RX4_DR3_N | 11132.52 | 13365.48 | 83.29 |
| PE_RX4_DR3_P | 11132.46 | 13365.48 | 83.29 |
| PE_RX4_DR4_N | 12502.67 | 16790.68 | 74.459999999999994 |
| PE_RX4_DR4_P | 12502.65 | 16790.68 | 74.459999999999994 |
| PE_RX4_DR5_N | 2727.81 | 3306.27 | 82.5 |
| PE_RX4_DR5_P | 2727.8 | 3306.28 | 82.5 |
| PE_RX4_DR6_N | 2203.2800000000002 | 2668.47 | 82.57 |
| PE_RX4_DR6_P | 2203.2800000000002 | 2668.46 | 82.57 |
| PE_RX4_DR7_N | 2166.6799999999998 | 2719.81 | 79.66 |
| PE_RX4_DR7_P | 2166.69 | 2719.82 | 79.66 |
| PE_RX4_DR8_N | 2002.18 | 2538.71 | 78.87 |
| PE_RX4_DR8_P | 2002.05 | 2538.7199999999998 | 78.86 |
| PE_RX4_DR9_N | 6379.88 | 5995.4 | 106.41 |
| PE_RX4_DR9_P | 6380.04 | 5995.41 | 106.42 |
| PE_TX1_DR0_N | 10237.549999999999 | 10763.71 | 95.11 |
| PE_TX1_DR0_P | 10237.469999999999 | 10763.71 | 95.11 |
| PE_TX1_DR10_N | 3700.84 | 2677.88 | 138.19999999999999 |
| PE_TX1_DR10_P | 3700.77 | 2740.88 | 135.02000000000001 |
| PE_TX1_DR11_N | 1770.02 | 1378.66 | 128.38999999999999 |
| PE_TX1_DR11_P | 1770.09 | 1315.67 | 134.54 |
| PE_TX1_DR12_N | 4091.77 | 2032.2 | 201.35 |
| PE_TX1_DR12_P | 4091.73 | 1969.21 | 207.79 |
| PE_TX1_DR13_N | 2074.4499999999998 | 1845.76 | 112.39 |
| PE_TX1_DR13_P | 2074.4899999999998 | 1908.76 | 108.68 |
| PE_TX1_DR14_N | 5307.64 | 5270.96 | 100.7 |
| PE_TX1_DR14_P | 5307.54 | 5333.95 | 99.5 |
| PE_TX1_DR1_N | 9310.35 | 9665.43 | 96.33 |
| PE_TX1_DR1_P | 9310.06 | 9665.42 | 96.32 |
| PE_TX1_DR2_N | 9469.5 | 11027.64 | 85.87 |
| PE_TX1_DR2_P | 9469.5 | 11027.64 | 85.87 |
| PE_TX1_DR3_N | 11068.14 | 13885.91 | 79.709999999999994 |
| PE_TX1_DR3_P | 11068.01 | 13885.91 | 79.709999999999994 |
| PE_TX1_DR4_N | 12696.71 | 15531.58 | 81.75 |
| PE_TX1_DR4_P | 12696.61 | 15531.58 | 81.75 |
| PE_TX1_DR5_N | 2348.2800000000002 | 2629.86 | 89.29 |
| PE_TX1_DR5_P | 2348.75 | 2629.86 | 89.31 |
| PE_TX1_DR6_N | 1791.55 | 2118.04 | 84.59 |
| PE_TX1_DR6_P | 1791.56 | 2118.04 | 84.59 |
| PE_TX1_DR7_N | 2443.6 | 3051.27 | 80.08 |
| PE_TX1_DR7_P | 2443.6 | 3051.26 | 80.09 |
| PE_TX1_DR8_N | 2543.7399999999998 | 3185.13 | 79.86 |
| PE_TX1_DR8_P | 2543.7399999999998 | 3185.12 | 79.86 |
| PE_TX1_DR9_N | 6818.65 | 6452.85 | 105.67 |
| PE_TX1_DR9_P | 6818.66 | 6452.84 | 105.67 |
| PE_TX2_DR0_N | 10090.61 | 10889.7 | 92.66 |
| PE_TX2_DR0_P | 10090.709999999999 | 10889.69 | 92.66 |
| PE_TX2_DR10_N | 3154.16 | 2047.97 | 154.01 |
| PE_TX2_DR10_P | 3154.31 | 2110.9499999999998 | 149.43 |
| PE_TX2_DR11_N | 2296.17 | 869.38 | 264.12 |
| PE_TX2_DR11_P | 2296.29 | 932.37 | 246.29 |
| PE_TX2_DR12_N | 3622.09 | 1402.28 | 258.3 |
| PE_TX2_DR12_P | 3621.9 | 1339.29 | 270.43 |
| PE_TX2_DR13_N | 2721.55 | 2475.6799999999998 | 109.93 |
| PE_TX2_DR13_P | 2721.58 | 2538.67 | 107.21 |
| PE_TX2_DR14_N | 6012.78 | 5900.88 | 101.9 |
| PE_TX2_DR14_P | 6013.23 | 5963.87 | 100.83 |
| PE_TX2_DR1_N | 9071.08 | 9287.4699999999993 | 97.67 |
| PE_TX2_DR1_P | 9071.1 | 9287.48 | 97.67 |
| PE_TX2_DR2_N | 9545.4699999999993 | 10649.69 | 89.63 |
| PE_TX2_DR2_P | 9545.4500000000007 | 10649.69 | 89.63 |
| PE_TX2_DR3_N | 11051.2 | 13507.96 | 81.81 |
| PE_TX2_DR3_P | 11051.22 | 13507.96 | 81.81 |
| PE_TX2_DR4_N | 12696.17 | 15153.63 | 83.78 |
| PE_TX2_DR4_P | 12696.16 | 15153.63 | 83.78 |
| PE_TX2_DR5_N | 2609 | 3007.81 | 86.74 |
| PE_TX2_DR5_P | 2609.71 | 3007.81 | 86.76 |
| PE_TX2_DR6_N | 2419.59 | 2495.9899999999998 | 96.94 |
| PE_TX2_DR6_P | 2419.65 | 2495.9899999999998 | 96.94 |
| PE_TX2_DR7_N | 2072.41 | 2673.31 | 77.52 |
| PE_TX2_DR7_P | 2072.4299999999998 | 2673.32 | 77.52 |
| PE_TX2_DR8_N | 2171.15 | 2807.17 | 77.34 |
| PE_TX2_DR8_P | 2171.17 | 2807.18 | 77.34 |
| PE_TX2_DR9_N | 6464.39 | 6074.89 | 106.41 |
| PE_TX2_DR9_P | 6464.39 | 6074.9 | 106.41 |
| PE_TX3_DR0_N | 10190.1 | 10952.68 | 93.04 |
| PE_TX3_DR0_P | 10190.34 | 10952.69 | 93.04 |
| PE_TX3_DR10_N | 2929.6 | 1733 | 169.05 |
| PE_TX3_DR10_P | 2929.45 | 1796 | 163.11000000000001 |
| PE_TX3_DR11_N | 2657.73 | 1184.3399999999999 | 224.41 |
| PE_TX3_DR11_P | 2657.78 | 1247.33 | 213.08 |
| PE_TX3_DR12_N | 3455.21 | 1087.33 | 317.77 |
| PE_TX3_DR12_P | 3455.05 | 1024.33 | 337.3 |
| PE_TX3_DR13_N | 3089.45 | 2790.64 | 110.71 |
| PE_TX3_DR13_P | 3089.47 | 2853.63 | 108.26 |
| PE_TX3_DR14_N | 6317.21 | 6215.84 | 101.63 |
| PE_TX3_DR14_P | 6317.11 | 6278.83 | 100.61 |
| PE_TX3_DR1_N | 9008.67 | 9224.49 | 97.66 |
| PE_TX3_DR1_P | 9008.66 | 9224.48 | 97.66 |
| PE_TX3_DR2_N | 9627.23 | 10586.7 | 90.94 |
| PE_TX3_DR2_P | 9627.23 | 10586.7 | 90.94 |
| PE_TX3_DR3_N | 11070.82 | 13444.97 | 82.34 |
| PE_TX3_DR3_P | 11070.89 | 13444.97 | 82.34 |
| PE_TX3_DR4_N | 12489.01 | 16870.169999999998 | 74.03 |
| PE_TX3_DR4_P | 12488.12 | 16870.16 | 74.02 |
| PE_TX3_DR5_N | 2579.8000000000002 | 3070.8 | 84.01 |
| PE_TX3_DR5_P | 2580.5700000000002 | 3070.8 | 84.04 |
| PE_TX3_DR6_N | 2301.71 | 2558.98 | 89.95 |
| PE_TX3_DR6_P | 2301.71 | 2558.98 | 89.95 |
| PE_TX3_DR7_N | 2041.73 | 2610.33 | 78.22 |
| PE_TX3_DR7_P | 2041.74 | 2610.3200000000002 | 78.22 |
| PE_TX3_DR8_N | 2142.13 | 2744.19 | 78.06 |
| PE_TX3_DR8_P | 2142.14 | 2744.18 | 78.06 |
| PE_TX3_DR9_N | 6514.93 | 6200.88 | 105.06 |
| PE_TX3_DR9_P | 6514.93 | 6200.88 | 105.06 |
| PE_TX4_DR0_N | 10373.02 | 11015.68 | 94.17 |
| PE_TX4_DR0_P | 10372.61 | 11015.68 | 94.16 |
| PE_TX4_DR10_N | 2673.15 | 1418.04 | 188.51 |
| PE_TX4_DR10_P | 2673.07 | 1481.04 | 180.49 |
| PE_TX4_DR11_N | 2957.11 | 1499.3 | 197.23 |
| PE_TX4_DR11_P | 2956.79 | 1562.3 | 189.26 |
| PE_TX4_DR12_N | 3297.63 | 845.76 | 389.9 |
| PE_TX4_DR12_P | 3297.16 | 908.75 | 362.82 |
| PE_TX4_DR13_N | 3443.56 | 3105.6 | 110.88 |
| PE_TX4_DR13_P | 3443.49 | 3168.6 | 108.68 |
| PE_TX4_DR14_N | 6664.18 | 6530.8 | 102.04 |
| PE_TX4_DR14_P | 6664.19 | 6593.8 | 101.07 |
| PE_TX4_DR1_N | 8974.0400000000009 | 9161.49 | 97.95 |
| PE_TX4_DR1_P | 8974.0400000000009 | 9161.49 | 97.95 |
| PE_TX4_DR2_N | 9698.26 | 10523.7 | 92.16 |
| PE_TX4_DR2_P | 9698.23 | 10523.7 | 92.16 |
| PE_TX4_DR3_N | 11080.07 | 13381.97 | 82.8 |
| PE_TX4_DR3_P | 11080.03 | 13381.97 | 82.8 |
| PE_TX4_DR4_N | 12493.92 | 16807.169999999998 | 74.34 |
| PE_TX4_DR4_P | 12493.64 | 16807.169999999998 | 74.34 |
| PE_TX4_DR5_N | 2600.2399999999998 | 3133.8 | 82.97 |
| PE_TX4_DR5_P | 2601.0100000000002 | 3133.79 | 83 |
| PE_TX4_DR6_N | 2244.44 | 2621.97 | 85.6 |
| PE_TX4_DR6_P | 2244.4299999999998 | 2621.98 | 85.6 |
| PE_TX4_DR7_N | 1995.57 | 2547.33 | 78.34 |
| PE_TX4_DR7_P | 1995.57 | 2547.33 | 78.34 |
| PE_TX4_DR8_N | 2121.09 | 2681.19 | 79.11 |
| PE_TX4_DR8_P | 2121.09 | 2681.19 | 79.11 |
| PE_TX4_DR9_N | 6487.35 | 6137.89 | 105.69 |
| PE_TX4_DR9_P | 6487.28 | 6137.88 | 105.69 |
| PWM_EXP_A | 15075.65 | 10110.469999999999 | 149.11000000000001 |
| SAS_I2C_B_BUF_SCL_R | 4557.4799999999996 | 3295.41 | 138.30000000000001 |
| SAS_I2C_B_BUF_SDA_R | 4487.7299999999996 | 3286.91 | 136.53 |
| SAS_I2C_C_BUF_SCL_R | 12441.41 | 10689.39 | 116.39 |
| SAS_I2C_C_BUF_SDA_R | 12454.93 | 10770.88 | 115.64 |
| SCL_DR0 | 9300.24 | 10530.29 | 88.32 |
| SCL_DR1 | 6296.78 | 6599.66 | 95.41 |
| SCL_DR2 | 8293.19 | 8314.9699999999993 | 99.74 |
| SCL_DR3 | 6462.19 | 6829.97 | 94.62 |
| SCL_DR4 | 7864.53 | 8410 | 93.51 |
| SCL_DR5 | 6332.13 | 6859.97 | 92.31 |
| SCL_DR6 | 2726.5 | 2782.29 | 97.99 |
| SCL_DR7 | 5780.26 | 4539.97 | 127.32 |
| SCL_DR8 | 5052.32 | 3054.97 | 165.38 |
| SCL_DR9 | 5266.23 | 4267.29 | 123.41 |
| SCL_DR10 | 3346.84 | 4194.97 | 79.78 |
| SCL_DR11 | 3438.77 | 3319.66 | 103.59 |
| SCL_DR12 | 3826.69 | 4422.29 | 86.53 |
| SCL_DR13 | 3192.7 | 3009.97 | 106.07 |
| SCL_DR14 | 8061.91 | 6931.66 | 116.31 |
| SCL_DR0_R | 347.56 | 356.83 | 97.4 |
| SCL_DR10_R | 290.98 | 268.68 | 108.3 |
| SCL_DR11_R | 292.27999999999997 | 268.8 | 108.74 |
| SCL_DR12_R | 290.48 | 268.92 | 108.02 |
| SCL_DR13_R | 293.44 | 269.04000000000002 | 109.07 |
| SCL_DR14_R | 427.11 | 422.16 | 101.17 |
| SCL_DR1_R | 295.81 | 274.70999999999998 | 107.68 |
| SCL_DR2_R | 294.63 | 274.58999999999997 | 107.3 |
| SCL_DR3_R | 295.91000000000003 | 274.47000000000003 | 107.81 |
| SCL_DR4_R | 295.95999999999998 | 274.35000000000002 | 107.88 |
| SCL_DR5_R | 343.43 | 377.37 | 91.01 |
| SCL_DR6_R | 292.82 | 271.25 | 107.95 |
| SCL_DR7_R | 292.35000000000002 | 271.13 | 107.83 |
| SCL_DR8_R | 291.67 | 271.01 | 107.62 |
| SCL_DR9_R | 289.33 | 270.89 | 106.81 |
| SDA_DR0 | 9306.4699999999993 | 10602.97 | 87.77 |
| SDA_DR1 | 6288 | 6729.66 | 93.44 |
| SDA_DR2 | 8228.06 | 8242.2900000000009 | 99.83 |
| SDA_DR3 | 6412.07 | 6857.29 | 93.51 |
| SDA_DR4 | 7750.37 | 8340.32 | 92.93 |
| SDA_DR5 | 6435.06 | 7047.29 | 91.31 |
| SDA_DR6 | 2746.9 | 2832.29 | 96.99 |
| SDA_DR7 | 5720.16 | 4509.66 | 126.84 |
| SDA_DR8 | 4966.9799999999996 | 3082.29 | 161.15 |
| SDA_DR9 | 5181.7700000000004 | 4217.29 | 122.87 |
| SDA_DR10 | 3397.94 | 4176.34 | 81.36 |
| SDA_DR11 | 3508.13 | 3509.97 | 99.95 |
| SDA_DR12 | 3806.26 | 4394.97 | 86.6 |
| SDA_DR13 | 3176.35 | 3089.34 | 102.82 |
| SDA_DR14 | 8059.99 | 6861.97 | 117.46 |
| SDA_DR0_R | 346.31 | 338.32 | 102.36 |
| SDA_DR10_R | 288.58999999999997 | 269.55 | 107.06 |
| SDA_DR11_R | 287.29000000000002 | 269.43 | 106.63 |
| SDA_DR12_R | 289.23 | 269.31 | 107.4 |
| SDA_DR13_R | 286.13 | 269.19 | 106.29 |
| SDA_DR14_R | 461.32 | 503.65 | 91.6 |
| SDA_DR1_R | 292.58 | 272.33999999999997 | 107.43 |
| SDA_DR2_R | 293.76 | 272.45999999999998 | 107.82 |
| SDA_DR3_R | 292.48 | 272.58 | 107.3 |
| SDA_DR4_R | 292.43 | 272.7 | 107.24 |
| SDA_DR5_R | 346.6 | 358.86 | 96.58 |
| SDA_DR6_R | 288.64999999999998 | 268.88 | 107.35 |
| SDA_DR7_R | 289.12 | 269 | 107.48 |
| SDA_DR8_R | 289.8 | 269.12 | 107.68 |
| SDA_DR9_R | 292.14 | 269.24 | 108.5 |
| SD_LATCH_RELEASE | 17231.560000000001 | 15555.96 | 110.77 |
| SD_LATCH_RELEASE_R | 1839.1 | 1734.35 | 106.04 |
| SELF_1A&2A_HB | 12860.8 | 11168.82 | 115.15 |
| SELF_TRAY_PRESENT | 11990.48 | 11983.92 | 100.05 |
| SELF_TRAY_PRESENT_R | 1231.98 | 1263.45 | 97.51 |
| SSD0_CLK0_OE_MOS_N | 421.67 | 415.65 | 101.45 |
| SSD0_CLK0_OE_N | 6227.47 | 6468.17 | 96.28 |
| SSD0_CLK0_OE_R_N | 10376.02 | 9079.5400000000009 | 114.28 |
| SSD0_PERST_N | 12723.52 | 11125.52 | 114.36 |
| SSD0_PWREN | 13519.45 | 10598.55 | 127.56 |
| SSD0_PWREN_R | 113.25 | 113.25 | 100 |
| SSD10_CLK0_OE_MOS_N | 557.29999999999995 | 377.9 | 147.47 |
| SSD10_CLK0_OE_N | 4803.7299999999996 | 3516.2 | 136.62 |
| SSD10_CLK0_OE_R_N | 7432.79 | 7903.38 | 94.05 |
| SSD10_PERST_N | 3149 | 2898 | 108.66 |
| SSD10_PWREN | 2057.31 | 2113.4299999999998 | 97.34 |
| SSD10_PWREN_R | 113.25 | 113.25 | 100 |
| SSD11_CLK0_OE_MOS_N | 503.61 | 465.65 | 108.15 |
| SSD11_CLK0_OE_N | 4473.99 | 3251.08 | 137.62 |
| SSD11_CLK0_OE_R_N | 5799.28 | 6639.19 | 87.35 |
| SSD11_PERST_N | 3354.81 | 3142.09 | 106.77 |
| SSD11_PWREN | 2439.9699999999998 | 2509.2600000000002 | 97.24 |
| SSD11_PWREN_R | 113.25 | 113.25 | 100 |
| SSD12_CLK0_OE_MOS_N | 503.61 | 465.65 | 108.15 |
| SSD12_CLK0_OE_N | 4526.07 | 2910.96 | 155.47999999999999 |
| SSD12_CLK0_OE_R_N | 5285.32 | 6396.07 | 82.63 |
| SSD12_PERST_N | 2904.28 | 2656.42 | 109.33 |
| SSD12_PWREN | 5052.3599999999997 | 4722.9799999999996 | 106.97 |
| SSD12_PWREN_R | 151.75 | 157.75 | 96.19 |
| SSD13_CLK0_OE_MOS_N | 503.61 | 465.65 | 108.15 |
| SSD13_CLK0_OE_N | 4440 | 3155.84 | 140.69 |
| SSD13_CLK0_OE_R_N | 6078.53 | 7200.76 | 84.42 |
| SSD13_PERST_N | 2826.6 | 2964.26 | 95.36 |
| SSD13_PWREN | 5535.18 | 5328.66 | 103.88 |
| SSD13_PWREN_R | 113.25 | 113.25 | 100 |
| SSD14_CLK0_OE_MOS_N | 503.61 | 465.65 | 108.15 |
| SSD14_CLK0_OE_N | 6030.83 | 5587.5 | 107.93 |
| SSD14_CLK0_OE_R_N | 9733.67 | 9802.7800000000007 | 99.3 |
| SSD14_PERST_N | 8151.72 | 6813.91 | 119.63 |
| SSD14_PWREN | 8160.6 | 7793.39 | 104.71 |
| SSD14_PWREN_R | 113.25 | 113.25 | 100 |
| SSD1_CLK0_OE_MOS_N | 417.53 | 415.65 | 100.45 |
| SSD1_CLK0_OE_N | 6485.87 | 7398.05 | 87.67 |
| SSD1_CLK0_OE_R_N | 13028.35 | 13577.1 | 95.96 |
| SSD1_PERST_N | 12047.06 | 10657.16 | 113.04 |
| SSD1_PWREN | 13845.66 | 8501.43 | 162.86000000000001 |
| SSD1_PWREN_R | 113.25 | 113.25 | 100 |
| SSD2_CLK0_OE_MOS_N | 417.53 | 415.65 | 100.45 |
| SSD2_CLK0_OE_N | 6812.43 | 5674.11 | 120.06 |
| SSD2_CLK0_OE_R_N | 12062.72 | 12194.74 | 98.92 |
| SSD2_PERST_N | 11042.3 | 9262.7199999999993 | 119.21 |
| SSD2_PWREN | 9486.02 | 9474.01 | 100.13 |
| SSD2_PWREN_R | 113.25 | 113.25 | 100 |
| SSD3_CLK0_OE_MOS_N | 417.53 | 415.65 | 100.45 |
| SSD3_CLK0_OE_N | 7530.34 | 6069.23 | 124.07 |
| SSD3_CLK0_OE_R_N | 13659.96 | 14459.58 | 94.47 |
| SSD3_PERST_N | 12400.71 | 13523.31 | 91.7 |
| SSD3_PWREN | 10795.84 | 11733.74 | 92.01 |
| SSD3_PWREN_R | 113.25 | 113.25 | 100 |
| SSD4_CLK0_OE_MOS_N | 356.51 | 411.87 | 86.56 |
| SSD4_CLK0_OE_N | 9049.57 | 10134.35 | 89.3 |
| SSD4_CLK0_OE_R_N | 26435.54 | 15329.17 | 172.45 |
| SSD4_PERST_N | 15497 | 13735.16 | 112.83 |
| SSD4_PWREN | 18183.939999999999 | 12386.41 | 146.81 |
| SSD4_PWREN_R | 113.25 | 113.25 | 100 |
| SSD5_CLK0_OE_MOS_N | 539.79 | 640.94000000000005 | 84.22 |
| SSD5_CLK0_OE_N | 2749.13 | 3234.59 | 84.99 |
| SSD5_CLK0_OE_R_N | 5598.5 | 4613.43 | 121.35 |
| SSD5_PERST_N | 2820.93 | 2534.2199999999998 | 111.31 |
| SSD5_PWREN | 5458.36 | 3392.09 | 160.91 |
| SSD5_PWREN_R | 114.81 | 121.25 | 94.69 |
| SSD6_CLK0_OE_MOS_N | 497.33 | 477.41 | 104.17 |
| SSD6_CLK0_OE_N | 3481.96 | 4519.47 | 77.040000000000006 |
| SSD6_CLK0_OE_R_N | 5699.22 | 5732.08 | 99.43 |
| SSD6_PERST_N | 2189.3000000000002 | 2085.39 | 104.98 |
| SSD6_PWREN | 2350.15 | 2683.47 | 87.58 |
| SSD6_PWREN_R | 150.01 | 158.94 | 94.38 |
| SSD7_CLK0_OE_MOS_N | 531.91 | 545.83000000000004 | 97.45 |
| SSD7_CLK0_OE_N | 3372.78 | 4179.3500000000004 | 80.7 |
| SSD7_CLK0_OE_R_N | 7439.58 | 7809.28 | 95.27 |
| SSD7_PERST_N | 2999.93 | 3270.6 | 91.72 |
| SSD7_PWREN | 1548.84 | 1477.6 | 104.82 |
| SSD7_PWREN_R | 113.25 | 113.25 | 100 |
| SSD8_CLK0_OE_MOS_N | 581.57000000000005 | 435.9 | 133.41999999999999 |
| SSD8_CLK0_OE_N | 3441.04 | 4424.2299999999996 | 77.78 |
| SSD8_CLK0_OE_R_N | 7908.01 | 8486.48 | 93.18 |
| SSD8_PERST_N | 3797.09 | 4002.88 | 94.86 |
| SSD8_PWREN | 2010.08 | 2150.7800000000002 | 93.46 |
| SSD8_PWREN_R | 113.25 | 113.25 | 100 |
| SSD9_CLK0_OE_MOS_N | 508.81 | 517.41 | 98.34 |
| SSD9_CLK0_OE_N | 2988.55 | 2590.77 | 115.35 |
| SSD9_CLK0_OE_R_N | 9001.1299999999992 | 10608.37 | 84.85 |
| SSD9_PERST_N | 6162.74 | 6594.18 | 93.46 |
| SSD9_PWREN | 3818.24 | 3797.08 | 100.56 |
| SSD9_PWREN_R | 113.25 | 113.25 | 100 |
| SSD_ACT_DR0 | 1933.37 | 1751.13 | 110.41 |
| SSD_ACT_DR1 | 2029.68 | 1751.13 | 115.91 |
| SSD_ACT_DR2 | 1910.54 | 1751.12 | 109.1 |
| SSD_ACT_DR3 | 2016.83 | 1751.12 | 115.17 |
| SSD_ACT_DR4 | 2024.04 | 1761.12 | 114.93 |
| SSD_ACT_DR5 | 2131.8200000000002 | 2183.5500000000002 | 97.63 |
| SSD_ACT_DR6 | 2256.37 | 1756.13 | 128.49 |
| SSD_ACT_DR7 | 2131.75 | 1799.35 | 118.47 |
| SSD_ACT_DR8 | 1776.7 | 1894.23 | 93.8 |
| SSD_ACT_DR9 | 2312.12 | 1741.12 | 132.79 |
| SSD_ACT_DR10 | 2196.13 | 1797.02 | 122.21 |
| SSD_ACT_DR11 | 2283.2399999999998 | 1794.92 | 127.21 |
| SSD_ACT_DR12 | 2091.54 | 1782.9 | 117.31 |
| SSD_ACT_DR13 | 2270.4299999999998 | 1823.93 | 124.48 |
| SSD_ACT_DR14 | 2175.16 | 1823.93 | 119.26 |
| SSD_ACT_DR0_MOS_N | 421.38 | 467.77 | 90.08 |
| SSD_ACT_DR0_R | 212.66 | 86.25 | 246.56 |
| SSD_ACT_DR10_MOS_N | 985.48 | 703.94 | 140 |
| SSD_ACT_DR10_R | 133.22 | 134.25 | 99.24 |
| SSD_ACT_DR11_MOS_N | 628.54 | 526.70000000000005 | 119.34 |
| SSD_ACT_DR11_R | 156.41999999999999 | 162.68 | 96.15 |
| SSD_ACT_DR12_MOS_N | 644 | 517.89 | 124.35 |
| SSD_ACT_DR12_R | 164.4 | 167.8 | 97.98 |
| SSD_ACT_DR13_MOS_N | 451.43 | 450.07 | 100.3 |
| SSD_ACT_DR13_R | 157.55000000000001 | 162.68 | 96.85 |
| SSD_ACT_DR14_MOS_N | 560.14 | 557.83000000000004 | 100.41 |
| SSD_ACT_DR14_R | 157.97999999999999 | 162.68 | 97.11 |
| SSD_ACT_DR1_MOS_N | 434.64 | 467.77 | 92.92 |
| SSD_ACT_DR1_R | 214.13 | 86.25 | 248.26 |
| SSD_ACT_DR2_MOS_N | 441.96 | 467.77 | 94.48 |
| SSD_ACT_DR2_R | 214.13 | 86.25 | 248.26 |
| SSD_ACT_DR3_MOS_N | 421.09 | 467.77 | 90.02 |
| SSD_ACT_DR3_R | 214.13 | 86.25 | 248.26 |
| SSD_ACT_DR4_MOS_N | 428.42 | 467.77 | 91.59 |
| SSD_ACT_DR4_R | 204.13 | 76.25 | 267.70999999999998 |
| SSD_ACT_DR5_MOS_N | 363.26 | 309.69 | 117.3 |
| SSD_ACT_DR5_R | 153.13 | 175.29 | 87.36 |
| SSD_ACT_DR6_MOS_N | 511.07 | 554.15 | 92.23 |
| SSD_ACT_DR6_R | 219.59 | 81.25 | 270.26 |
| SSD_ACT_DR7_MOS_N | 242.56 | 281.45 | 86.18 |
| SSD_ACT_DR7_R | 138.56 | 145.41999999999999 | 95.28 |
| SSD_ACT_DR8_MOS_N | 383.76 | 405.88 | 94.55 |
| SSD_ACT_DR8_R | 163.85 | 91.25 | 179.56 |
| SSD_ACT_DR9_MOS_N | 525.52 | 513.58000000000004 | 102.32 |
| SSD_ACT_DR9_R | 238.92 | 70.180000000000007 | 340.44 |
| SSD_PRSNT0 | 376.08 | 374.45 | 100.44 |
| SSD_PRSNT1 | 376.08 | 374.45 | 100.44 |
| SSD_PRSNT2 | 377.74 | 374.45 | 100.88 |
| SSD_PRSNT3 | 388.64 | 459.75 | 84.53 |
| SSD_PRSNT4 | 352.39 | 372.25 | 94.67 |
| SSD_PRSNT5 | 398.99 | 399.75 | 99.81 |
| SSD_PRSNT6 | 388.64 | 459.75 | 84.53 |
| SSD_PRSNT7 | 388.64 | 459.75 | 84.53 |
| SSD_PRSNT8 | 388.64 | 459.75 | 84.53 |
| SSD_PRSNT9 | 399.14 | 485.1 | 82.28 |
| SSD_PRSNT10 | 399.14 | 485.1 | 82.28 |
| SSD_PRSNT11 | 398.99 | 399.75 | 99.81 |
| SSD_PRSNT12 | 397.18 | 399.75 | 99.36 |
| SSD_PRSNT13 | 397.18 | 399.75 | 99.36 |
| SSD_PRSNT14 | 376.08 | 374.45 | 100.44 |
| SSD_PRSNT_NET0 | 6607.36 | 6848.17 | 96.48 |
| SSD_PRSNT_NET1 | 6871 | 7778.05 | 88.34 |
| SSD_PRSNT_NET2 | 7217.65 | 5454.11 | 132.33000000000001 |
| SSD_PRSNT_NET3 | 7764.71 | 5689.23 | 136.47999999999999 |
| SSD_PRSNT_NET4 | 9454.7800000000007 | 9914.35 | 95.36 |
| SSD_PRSNT_NET5 | 3082.26 | 3614.59 | 85.27 |
| SSD_PRSNT_NET6 | 3841.89 | 4899.47 | 78.41 |
| SSD_PRSNT_NET7 | 3705.92 | 4559.3500000000004 | 81.28 |
| SSD_PRSNT_NET8 | 3802.44 | 4804.2299999999996 | 79.150000000000006 |
| SSD_PRSNT_NET9 | 3201.36 | 2210.77 | 144.81 |
| SSD_PRSNT_NET10 | 5062.04 | 3136.2 | 161.41 |
| SSD_PRSNT_NET11 | 4903.01 | 3031.08 | 161.76 |
| SSD_PRSNT_NET12 | 4935.7299999999996 | 2882.26 | 171.25 |
| SSD_PRSNT_NET13 | 4862.91 | 2935.84 | 165.64 |
| SSD_PRSNT_NET14 | 6419.4 | 5807.5 | 110.54 |
| SW_SSD0_N | 315.91000000000003 | 337 | 93.74 |
| SW_SSD0_R | 284.93 | 282.5 | 100.86 |
| SW_SSD10_N | 290.36 | 305 | 95.2 |
| SW_SSD10_R | 286.33999999999997 | 282.5 | 101.36 |
| SW_SSD11_N | 290.36 | 305 | 95.2 |
| SW_SSD11_R | 286.33999999999997 | 282.5 | 101.36 |
| SW_SSD12_N | 290.36 | 305 | 95.2 |
| SW_SSD12_R | 292 | 282.5 | 103.36 |
| SW_SSD13_N | 290.36 | 305 | 95.2 |
| SW_SSD13_R | 286.33999999999997 | 282.5 | 101.36 |
| SW_SSD14_N | 290.36 | 305 | 95.2 |
| SW_SSD14_R | 284 | 282.5 | 100.53 |
| SW_SSD1_N | 290.36 | 305 | 95.2 |
| SW_SSD1_R | 286.83 | 282.5 | 101.53 |
| SW_SSD2_N | 290.36 | 305 | 95.2 |
| SW_SSD2_R | 286.33999999999997 | 282.5 | 101.36 |
| SW_SSD3_N | 290.36 | 305 | 95.2 |
| SW_SSD3_R | 286.33999999999997 | 282.5 | 101.36 |
| SW_SSD4_N | 290.36 | 305 | 95.2 |
| SW_SSD4_R | 286.33999999999997 | 282.5 | 101.36 |
| SW_SSD5_N | 315.36 | 330 | 95.56 |
| SW_SSD5_R | 286.33999999999997 | 282.5 | 101.36 |
| SW_SSD6_N | 316.95 | 348 | 91.08 |
| SW_SSD6_R | 284.58 | 282.5 | 100.74 |
| SW_SSD7_N | 290.36 | 305 | 95.2 |
| SW_SSD7_R | 286.33999999999997 | 282.5 | 101.36 |
| SW_SSD8_N | 290.36 | 305 | 95.2 |
| SW_SSD8_R | 286.33999999999997 | 282.5 | 101.36 |
| SW_SSD9_N | 290.36 | 305 | 95.2 |
| SW_SSD9_R | 286.33999999999997 | 282.5 | 101.36 |
| TMP1_SCL | 317.97000000000003 | 341.99 | 92.98 |
| TMP1_SDA | 317.8 | 327.58999999999997 | 97.01 |
| TMP2_SCL | 210.38 | 192.67 | 109.19 |
| TMP2_SDA | 209.18 | 189.73 | 110.25 |
| TMP3_SCL | 209.66 | 190.93 | 109.81 |
| TMP3_SDA | 209.9 | 191.47 | 109.62 |
| TMP4_SCL | 204.64 | 191.13 | 107.07 |
| TMP4_SDA | 207.86 | 187.41 | 110.91 |
| TPS53312_P3V3_PG | 452.3 | 471.91 | 95.85 |
| TRAY_ID | 17266.47 | 15615.96 | 110.57 |
| TRAY_ID_R | 1894.73 | 1805.84 | 104.92 |
| VDDA_1 | 302.69 | 340.68 | 88.85 |
| VDDA_2 | 302.69 | 340.68 | 88.85 |
| VDDA_3 | 302.69 | 340.68 | 88.85 |
| VDDA_4 | 302.69 | 340.68 | 88.85 |
| VDDR_1 | 257.08 | 276.5 | 92.98 |
| VDDR_2 | 257.08 | 276.5 | 92.98 |
| VDDR_3 | 257.5 | 277.5 | 92.79 |
| VDDR_4 | 257.5 | 277.5 | 92.79 |
| VDD_DIFF_1 | 533.09 | 2505.6 | 21.28 |
| VDD_DIFF_2 | 535.41999999999996 | 2503.1 | 21.39 |
| VDD_DIFF_3 | 611.05999999999995 | 2473.3000000000002 | 24.71 |
| VDD_DIFF_4 | 560.01 | 2512.4 | 22.29 |
| VDD_IO_1 | 549.9 | 1068.98 | 51.44 |
| VDD_IO_2 | 688.99 | 1281.8 | 53.75 |
| VDD_IO_3 | 592.16999999999996 | 1151.5 | 51.43 |
| VDD_IO_4 | 621.69000000000005 | 1156.8 | 53.74 |
| VOL_SEN_ADDR | 179.55 | 191.65 | 93.69 |
| VOL_SEN_ALERT | 182.09 | 190.7 | 95.48 |
| VOL_SEN_SCL | 216.12 | 251.65 | 85.88 |
| VOL_SEN_SDA | 207.69 | 231.3 | 89.79 |
